FILE_TYPE = MULTI_PHYS_TABLE;

PART 'CONN2_AAABAT029Y19'

{========================================================================================}
:VALUE                   | PART_TYPE | MATERIAL | PART_NUMBER      = STANDARD | LIFECYCLE | PART_NUMBER   | JEDEC_TYPE                  | DESCRIPTION                                    | MANUFTR | MANUF_PN          | RD_CMPLS_LVL | CMPLS_LVL | CLASS | DIP_SMD | FROM_PJ        | DATA                      | FP_ECN                | EE_CHECK_LIST | CREATOR | CREATEDAY  | PSL | STATUS | ESD_CDM | ESD_HBM | ESD_MM | MSD  | PIN_LENGTH_LONG_PIN | PIN_LENGTH_SHORT_PIN ;
{========================================================================================}
 'CONN2_AAA-BAT-029-Y19' | 'THLF'    | 'IO'     | 'DFHS02FR062'(!) = ''       | ''        | 'DFHS02FR062' |'BATTERY_AAA-BAT-029-Y19'| 'CONN DIP HOUSING 2P 1R FR(P20,H8.80)'         | 'LTS'   | 'AAA-BAT-029-Y19' | 'EP(V1)'     | 'EP(V1)'  | 'IO'  | 'DIP'   | 'S1L-LI-JYUAN' | 'LTS_AAA-BAT-029-Y19.pdf' | 'AAA-BAT-029-Y19.msg' | ''            | ''      | '20200909' | ''  | ''     | 'NA'    | 'NA'    | 'NA'   | 'NA' | '124 MILS'          | '124 MILS'          
 'CONN2_AAA-BAT-029-Y19' | 'THLF'    | 'EMPTY'  | 'DFHS02FR062'(!) = ''       | ''        | 'DFHS02FR062' |'BATTERY_AAA-BAT-029-Y19'| 'CONN DIP HOUSING 2P 1R FR(P20,H8.80)'         | 'LTS'   | 'AAA-BAT-029-Y19' | 'EP(V1)'     | 'EP(V1)'  | 'IO'  | 'DIP'   | 'S1L-LI-JYUAN' | 'LTS_AAA-BAT-029-Y19.pdf' | 'AAA-BAT-029-Y19.msg' | ''            | ''      | '20200909' | ''  | ''     | 'NA'    | 'NA'    | 'NA'   | 'NA' | '124 MILS'          | '124 MILS'          
 'CONN2_AAA-BAT-029-Y19' | 'THLF'    | 'IO'     | 'SP_DFHS02FR062'(!) = ''       | ''        | 'DFHS02FR062' |'G_BATTERY_AAA-BAT-029-Y19'| 'CONN DIP HOUSING 2P 1R FR(P20,H8.80)_FOR SEL' | 'LTS'   | 'AAA-BAT-029-Y19' | 'EP(V1)'     | 'EP(V1)'  | 'IO'  | 'DIP'   | 'S8Z-VINCENT'  | 'LTS_AAA-BAT-029-Y19.pdf' | 'AAA-BAT-029-Y19.msg' | ''            | ''      | '20221201' | ''  | ''     | 'NA'    | 'NA'    | 'NA'   | 'NA' | '124 MILS'          | '124 MILS'          
 'CONN2_AAA-BAT-029-Y19' | 'THLF'    | 'EMPTY'  | 'SP_DFHS02FR062'(!) = ''       | ''        | 'DFHS02FR062' |'G_BATTERY_AAA-BAT-029-Y19'| 'CONN DIP HOUSING 2P 1R FR(P20,H8.80)_FOR SEL' | 'LTS'   | 'AAA-BAT-029-Y19' | 'EP(V1)'     | 'EP(V1)'  | 'IO'  | 'DIP'   | 'S8Z-VINCENT'  | 'LTS_AAA-BAT-029-Y19.pdf' | 'AAA-BAT-029-Y19.msg' | ''            | ''      | '20221201' | ''  | ''     | 'NA'    | 'NA'    | 'NA'   | 'NA' | '124 MILS'          | '124 MILS'          

END_PART

END.

